# T6G (Grand Teton) — schematic netlist excerpt (pin names and nets, part order shuffled) for the footprints in the layout excerpt that follows; sources: Cadence DE-HDL packaged netlist, KiCad conversion of 04192023_DAF0TMB3IC0_F0TG_MB_C_brd_V02_OCP.brd

PC9  Q_CAP  0.1UF 25V 10% X7R  pkg 0402  page 207 : A = PVDD11_S3_P0_VCCS ; B = GND
R1343  Q_RES  4.7K 5% EMPTY  pkg 0402LF  page 171 : A = P3V3_AUX ; B = SCM_JTAG_MUX_S1

(kicad_pcb
	(version 20260206)
	(generator "pcbnew")
	(generator_version "10.0")
	(general
		(thickness 1.6)
		(legacy_teardrops no)
	)
	(paper "A4")
	(title_block
		(title "04192023_DAF0TMB3IC0_F0TG_MB_C_brd_V02_OCP.brd")
		(comment 1 "Grand Teton / footprints 1399-1400 of 8354")
	)
	(layers
		(0 "F.Cu" signal "TOP")
		(4 "In1.Cu" signal "GND")
		(6 "In2.Cu" signal "IN1")
		(8 "In3.Cu" signal "GND1")
		(10 "In4.Cu" signal "IN2")
		(12 "In5.Cu" signal "GND2")
		(14 "In6.Cu" signal "IN3")
		(16 "In7.Cu" signal "GND3")
		(18 "In8.Cu" signal "VCC")
		(20 "In9.Cu" signal "VCC1")
		(22 "In10.Cu" signal "GND4")
		(24 "In11.Cu" signal "IN4")
		(26 "In12.Cu" signal "GND5")
		(28 "In13.Cu" signal "IN5")
		(30 "In14.Cu" signal "GND6")
		(32 "In15.Cu" signal "IN6")
		(34 "In16.Cu" signal "GND7")
		(2 "B.Cu" signal "BOTTOM")
		(9 "F.Adhes" user "F.Adhesive")
		(11 "B.Adhes" user "B.Adhesive")
		(13 "F.Paste" user "Package Geometry/Pastemask Top")
		(15 "B.Paste" user "Package Geometry/Pastemask Bottom")
		(5 "F.SilkS" user "Ref Des/Silkscreen Top")
		(7 "B.SilkS" user "Ref Des/Silkscreen Bottom")
		(1 "F.Mask" user "Board Geometry/Soldermask Top")
		(3 "B.Mask" user "Board Geometry/Soldermask Bottom")
		(17 "Dwgs.User" user "User.Drawings")
		(19 "Cmts.User" user "User.Comments")
		(21 "Eco1.User" user "User.Eco1")
		(23 "Eco2.User" user "User.Eco2")
		(25 "Edge.Cuts" user "Board Geometry/Outline")
		(27 "Margin" user)
		(31 "F.CrtYd" user "Package Geometry/Place Bound Top")
		(29 "B.CrtYd" user "Package Geometry/Place Bound Bottom")
		(35 "F.Fab" user "Ref Des/Assembly Top")
		(33 "B.Fab" user "Ref Des/Assembly Bottom")
	)
	(footprint ""
		(layer "F.Cu")
		(at 429.276764 -355.997764 90)
		(property "Reference" "PC9"
			(at 0 0 90)
			(layer "F.SilkS")
			(hide yes)
			(effects
				(font
					(size 1.27 1.27)
				)
			)
		)
		(property "Value" ""
			(at 0 0 90)
			(layer "F.Fab")
			(effects
				(font
					(size 1.27 1.27)
				)
			)
		)
		(duplicate_pad_numbers_are_jumpers no)
		(fp_line
			(start 0.7874 -0.4064)
			(end 0.7874 0.4064)
			(stroke
				(width 0.1524)
				(type default)
			)
			(layer "F.SilkS")
		)
		(fp_line
			(start -0.7874 -0.4064)
			(end 0.7874 -0.4064)
			(stroke
				(width 0.1524)
				(type default)
			)
			(layer "F.SilkS")
		)
		(fp_line
			(start 0.7874 0.4064)
			(end -0.7874 0.4064)
			(stroke
				(width 0.1524)
				(type default)
			)
			(layer "F.SilkS")
		)
		(fp_line
			(start -0.7874 0.4064)
			(end -0.7874 -0.4064)
			(stroke
				(width 0.1524)
				(type default)
			)
			(layer "F.SilkS")
		)
		(fp_line
			(start -0.12065 -0.305054)
			(end -0.12065 -0.2794)
			(stroke
				(width 0.1)
				(type default)
			)
			(layer "F.Fab")
		)
		(fp_line
			(start -0.67945 -0.305054)
			(end -0.12065 -0.305054)
			(stroke
				(width 0.1)
				(type default)
			)
			(layer "F.Fab")
		)
		(fp_line
			(start 0.67945 -0.3048)
			(end 0.67945 0.3048)
			(stroke
				(width 0.1)
				(type default)
			)
			(layer "F.Fab")
		)
		(fp_line
			(start 0.12065 -0.3048)
			(end 0.67945 -0.3048)
			(stroke
				(width 0.1)
				(type default)
			)
			(layer "F.Fab")
		)
		(fp_line
			(start 0.12065 -0.2794)
			(end 0.12065 -0.3048)
			(stroke
				(width 0.1)
				(type default)
			)
			(layer "F.Fab")
		)
		(fp_line
			(start -0.12065 -0.2794)
			(end 0.12065 -0.2794)
			(stroke
				(width 0.1)
				(type default)
			)
			(layer "F.Fab")
		)
		(fp_line
			(start 0.120396 0.2794)
			(end -0.12065 0.2794)
			(stroke
				(width 0.1)
				(type default)
			)
			(layer "F.Fab")
		)
		(fp_line
			(start -0.12065 0.2794)
			(end -0.12065 0.3048)
			(stroke
				(width 0.1)
				(type default)
			)
			(layer "F.Fab")
		)
		(fp_line
			(start 0.67945 0.3048)
			(end 0.120396 0.3048)
			(stroke
				(width 0.1)
				(type default)
			)
			(layer "F.Fab")
		)
		(fp_line
			(start 0.120396 0.3048)
			(end 0.120396 0.2794)
			(stroke
				(width 0.1)
				(type default)
			)
			(layer "F.Fab")
		)
		(fp_line
			(start -0.12065 0.3048)
			(end -0.67945 0.3048)
			(stroke
				(width 0.1)
				(type default)
			)
			(layer "F.Fab")
		)
		(fp_line
			(start -0.67945 0.3048)
			(end -0.67945 -0.305054)
			(stroke
				(width 0.1)
				(type default)
			)
			(layer "F.Fab")
		)
		(pad "1" smd circle
			(at -0.40005 0 90)
			(size 0 0)
			(layers "F.Cu" "F.Mask" "F.Paste")
			(net "PVDD11_S3_P0_VCCS")
		)
		(pad "2" smd circle
			(at 0.40005 0 90)
			(size 0 0)
			(layers "F.Cu" "F.Mask" "F.Paste")
			(net "GND")
		)
	)
	(footprint ""
		(layer "F.Cu")
		(at 318.300608 -22.57933 90)
		(property "Reference" "R1343"
			(at 0 0 90)
			(layer "F.SilkS")
			(hide yes)
			(effects
				(font
					(size 1.27 1.27)
				)
			)
		)
		(property "Value" ""
			(at 0 0 90)
			(layer "F.Fab")
			(effects
				(font
					(size 1.27 1.27)
				)
			)
		)
		(duplicate_pad_numbers_are_jumpers no)
		(fp_line
			(start 0.7874 -0.4064)
			(end 0.7874 0.4064)
			(stroke
				(width 0.1524)
				(type default)
			)
			(layer "F.SilkS")
		)
		(fp_line
			(start -0.7874 -0.4064)
			(end 0.7874 -0.4064)
			(stroke
				(width 0.1524)
				(type default)
			)
			(layer "F.SilkS")
		)
		(fp_line
			(start 0.7874 0.4064)
			(end -0.7874 0.4064)
			(stroke
				(width 0.1524)
				(type default)
			)
			(layer "F.SilkS")
		)
		(fp_line
			(start -0.7874 0.4064)
			(end -0.7874 -0.4064)
			(stroke
				(width 0.1524)
				(type default)
			)
			(layer "F.SilkS")
		)
		(fp_line
			(start -0.12065 -0.305054)
			(end -0.12065 -0.2794)
			(stroke
				(width 0.1)
				(type default)
			)
			(layer "F.Fab")
		)
		(fp_line
			(start -0.67945 -0.305054)
			(end -0.12065 -0.305054)
			(stroke
				(width 0.1)
				(type default)
			)
			(layer "F.Fab")
		)
		(fp_line
			(start 0.67945 -0.3048)
			(end 0.67945 0.3048)
			(stroke
				(width 0.1)
				(type default)
			)
			(layer "F.Fab")
		)
		(fp_line
			(start 0.12065 -0.3048)
			(end 0.67945 -0.3048)
			(stroke
				(width 0.1)
				(type default)
			)
			(layer "F.Fab")
		)
		(fp_line
			(start 0.12065 -0.2794)
			(end 0.12065 -0.3048)
			(stroke
				(width 0.1)
				(type default)
			)
			(layer "F.Fab")
		)
		(fp_line
			(start -0.12065 -0.2794)
			(end 0.12065 -0.2794)
			(stroke
				(width 0.1)
				(type default)
			)
			(layer "F.Fab")
		)
		(fp_line
			(start 0.120396 0.2794)
			(end -0.12065 0.2794)
			(stroke
				(width 0.1)
				(type default)
			)
			(layer "F.Fab")
		)
		(fp_line
			(start -0.12065 0.2794)
			(end -0.12065 0.3048)
			(stroke
				(width 0.1)
				(type default)
			)
			(layer "F.Fab")
		)
		(fp_line
			(start 0.67945 0.3048)
			(end 0.120396 0.3048)
			(stroke
				(width 0.1)
				(type default)
			)
			(layer "F.Fab")
		)
		(fp_line
			(start 0.120396 0.3048)
			(end 0.120396 0.2794)
			(stroke
				(width 0.1)
				(type default)
			)
			(layer "F.Fab")
		)
		(fp_line
			(start -0.12065 0.3048)
			(end -0.67945 0.3048)
			(stroke
				(width 0.1)
				(type default)
			)
			(layer "F.Fab")
		)
		(fp_line
			(start -0.67945 0.3048)
			(end -0.67945 -0.305054)
			(stroke
				(width 0.1)
				(type default)
			)
			(layer "F.Fab")
		)
		(pad "1" smd circle
			(at -0.40005 0 90)
			(size 0 0)
			(layers "F.Cu" "F.Mask" "F.Paste")
			(net "P3V3_AUX")
		)
		(pad "2" smd circle
			(at 0.40005 0 90)
			(size 0 0)
			(layers "F.Cu" "F.Mask" "F.Paste")
			(net "SCM_JTAG_MUX_S1")
		)
	)
)
